# S9S_MB_2U (Grand Teton) — schematic netlist excerpt (pin names and nets, part order shuffled) for the footprints in the layout excerpt that follows; sources: Cadence DE-HDL packaged netlist, KiCad conversion of 03242023_DA0F0TMBIJ0_F0T_Motherboard_J_brd_V01_OCP.brd

R3464  Q_RES  54.9K 1% CHIP  pkg 0402LF  page 147 : A = P3V3_AUX ; B = GPU_FPGA_OVERT_N
R445  Q_RES  0 5% CHIP  pkg 0402LF  page 153 : A = OCP_SFF_USB2_3_DP ; B = USB2_3_DP

(kicad_pcb
	(version 20260206)
	(generator "pcbnew")
	(generator_version "10.0")
	(general
		(thickness 1.6)
		(legacy_teardrops no)
	)
	(paper "A4")
	(title_block
		(title "03242023_DA0F0TMBIJ0_F0T_Motherboard_J_brd_V01_OCP.brd")
		(comment 1 "Grand Teton / footprints 3224-3225 of 6105")
	)
	(layers
		(0 "F.Cu" signal "TOP")
		(4 "In1.Cu" signal "GND")
		(6 "In2.Cu" signal "IN1")
		(8 "In3.Cu" signal "GND1")
		(10 "In4.Cu" signal "IN2")
		(12 "In5.Cu" signal "GND2")
		(14 "In6.Cu" signal "IN3")
		(16 "In7.Cu" signal "GND3")
		(18 "In8.Cu" signal "VCC")
		(20 "In9.Cu" signal "VCC1")
		(22 "In10.Cu" signal "GND4")
		(24 "In11.Cu" signal "IN4")
		(26 "In12.Cu" signal "GND5")
		(28 "In13.Cu" signal "IN5")
		(30 "In14.Cu" signal "GND6")
		(32 "In15.Cu" signal "IN6")
		(34 "In16.Cu" signal "GND7")
		(2 "B.Cu" signal "BOTTOM")
		(9 "F.Adhes" user "F.Adhesive")
		(11 "B.Adhes" user "B.Adhesive")
		(13 "F.Paste" user "Package Geometry/Pastemask Top")
		(15 "B.Paste" user "Package Geometry/Pastemask Bottom")
		(5 "F.SilkS" user "Ref Des/Silkscreen Top")
		(7 "B.SilkS" user "Ref Des/Silkscreen Bottom")
		(1 "F.Mask" user "Board Geometry/Soldermask Top")
		(3 "B.Mask" user "Board Geometry/Soldermask Bottom")
		(17 "Dwgs.User" user "User.Drawings")
		(19 "Cmts.User" user "User.Comments")
		(21 "Eco1.User" user "User.Eco1")
		(23 "Eco2.User" user "User.Eco2")
		(25 "Edge.Cuts" user "Board Geometry/Outline")
		(27 "Margin" user)
		(31 "F.CrtYd" user "Package Geometry/Place Bound Top")
		(29 "B.CrtYd" user "Package Geometry/Place Bound Bottom")
		(35 "F.Fab" user "Ref Des/Assembly Top")
		(33 "B.Fab" user "Ref Des/Assembly Bottom")
	)
	(footprint ""
		(layer "F.Cu")
		(at 387.262116 -14.25321 90)
		(property "Reference" "R445"
			(at 0 0 90)
			(layer "F.SilkS")
			(hide yes)
			(effects
				(font
					(size 1.27 1.27)
				)
			)
		)
		(property "Value" ""
			(at 0 0 90)
			(layer "F.Fab")
			(effects
				(font
					(size 1.27 1.27)
				)
			)
		)
		(duplicate_pad_numbers_are_jumpers no)
		(fp_line
			(start 0.7874 -0.4064)
			(end 0.7874 0.4064)
			(stroke
				(width 0.1524)
				(type default)
			)
			(layer "F.SilkS")
		)
		(fp_line
			(start -0.7874 -0.4064)
			(end 0.7874 -0.4064)
			(stroke
				(width 0.1524)
				(type default)
			)
			(layer "F.SilkS")
		)
		(fp_line
			(start 0.7874 0.4064)
			(end -0.7874 0.4064)
			(stroke
				(width 0.1524)
				(type default)
			)
			(layer "F.SilkS")
		)
		(fp_line
			(start -0.7874 0.4064)
			(end -0.7874 -0.4064)
			(stroke
				(width 0.1524)
				(type default)
			)
			(layer "F.SilkS")
		)
		(fp_line
			(start -0.12065 -0.305054)
			(end -0.12065 -0.2794)
			(stroke
				(width 0.1)
				(type default)
			)
			(layer "F.Fab")
		)
		(fp_line
			(start -0.67945 -0.305054)
			(end -0.12065 -0.305054)
			(stroke
				(width 0.1)
				(type default)
			)
			(layer "F.Fab")
		)
		(fp_line
			(start 0.67945 -0.3048)
			(end 0.67945 0.3048)
			(stroke
				(width 0.1)
				(type default)
			)
			(layer "F.Fab")
		)
		(fp_line
			(start 0.12065 -0.3048)
			(end 0.67945 -0.3048)
			(stroke
				(width 0.1)
				(type default)
			)
			(layer "F.Fab")
		)
		(fp_line
			(start 0.12065 -0.2794)
			(end 0.12065 -0.3048)
			(stroke
				(width 0.1)
				(type default)
			)
			(layer "F.Fab")
		)
		(fp_line
			(start -0.12065 -0.2794)
			(end 0.12065 -0.2794)
			(stroke
				(width 0.1)
				(type default)
			)
			(layer "F.Fab")
		)
		(fp_line
			(start 0.120396 0.2794)
			(end -0.12065 0.2794)
			(stroke
				(width 0.1)
				(type default)
			)
			(layer "F.Fab")
		)
		(fp_line
			(start -0.12065 0.2794)
			(end -0.12065 0.3048)
			(stroke
				(width 0.1)
				(type default)
			)
			(layer "F.Fab")
		)
		(fp_line
			(start 0.67945 0.3048)
			(end 0.120396 0.3048)
			(stroke
				(width 0.1)
				(type default)
			)
			(layer "F.Fab")
		)
		(fp_line
			(start 0.120396 0.3048)
			(end 0.120396 0.2794)
			(stroke
				(width 0.1)
				(type default)
			)
			(layer "F.Fab")
		)
		(fp_line
			(start -0.12065 0.3048)
			(end -0.67945 0.3048)
			(stroke
				(width 0.1)
				(type default)
			)
			(layer "F.Fab")
		)
		(fp_line
			(start -0.67945 0.3048)
			(end -0.67945 -0.305054)
			(stroke
				(width 0.1)
				(type default)
			)
			(layer "F.Fab")
		)
		(pad "1" smd circle
			(at -0.40005 0 90)
			(size 0 0)
			(layers "F.Cu" "F.Mask" "F.Paste")
			(net "OCP_SFF_USB2_3_DP")
		)
		(pad "2" smd circle
			(at 0.40005 0 90)
			(size 0 0)
			(layers "F.Cu" "F.Mask" "F.Paste")
			(net "USB2_3_DP")
		)
	)
	(footprint ""
		(layer "F.Cu")
		(at 424.223942 -396.635478)
		(property "Reference" "R3464"
			(at 0 0 0)
			(layer "F.SilkS")
			(hide yes)
			(effects
				(font
					(size 1.27 1.27)
				)
			)
		)
		(property "Value" ""
			(at 0 0 0)
			(layer "F.Fab")
			(effects
				(font
					(size 1.27 1.27)
				)
			)
		)
		(duplicate_pad_numbers_are_jumpers no)
		(fp_line
			(start -0.7874 -0.4064)
			(end 0.7874 -0.4064)
			(stroke
				(width 0.1524)
				(type default)
			)
			(layer "F.SilkS")
		)
		(fp_line
			(start -0.7874 0.4064)
			(end -0.7874 -0.4064)
			(stroke
				(width 0.1524)
				(type default)
			)
			(layer "F.SilkS")
		)
		(fp_line
			(start 0.7874 -0.4064)
			(end 0.7874 0.4064)
			(stroke
				(width 0.1524)
				(type default)
			)
			(layer "F.SilkS")
		)
		(fp_line
			(start 0.7874 0.4064)
			(end -0.7874 0.4064)
			(stroke
				(width 0.1524)
				(type default)
			)
			(layer "F.SilkS")
		)
		(fp_line
			(start -0.67945 -0.305054)
			(end -0.12065 -0.305054)
			(stroke
				(width 0.1)
				(type default)
			)
			(layer "F.Fab")
		)
		(fp_line
			(start -0.67945 0.3048)
			(end -0.67945 -0.305054)
			(stroke
				(width 0.1)
				(type default)
			)
			(layer "F.Fab")
		)
		(fp_line
			(start -0.12065 -0.305054)
			(end -0.12065 -0.2794)
			(stroke
				(width 0.1)
				(type default)
			)
			(layer "F.Fab")
		)
		(fp_line
			(start -0.12065 -0.2794)
			(end 0.12065 -0.2794)
			(stroke
				(width 0.1)
				(type default)
			)
			(layer "F.Fab")
		)
		(fp_line
			(start -0.12065 0.2794)
			(end -0.12065 0.3048)
			(stroke
				(width 0.1)
				(type default)
			)
			(layer "F.Fab")
		)
		(fp_line
			(start -0.12065 0.3048)
			(end -0.67945 0.3048)
			(stroke
				(width 0.1)
				(type default)
			)
			(layer "F.Fab")
		)
		(fp_line
			(start 0.120396 0.2794)
			(end -0.12065 0.2794)
			(stroke
				(width 0.1)
				(type default)
			)
			(layer "F.Fab")
		)
		(fp_line
			(start 0.120396 0.3048)
			(end 0.120396 0.2794)
			(stroke
				(width 0.1)
				(type default)
			)
			(layer "F.Fab")
		)
		(fp_line
			(start 0.12065 -0.3048)
			(end 0.67945 -0.3048)
			(stroke
				(width 0.1)
				(type default)
			)
			(layer "F.Fab")
		)
		(fp_line
			(start 0.12065 -0.2794)
			(end 0.12065 -0.3048)
			(stroke
				(width 0.1)
				(type default)
			)
			(layer "F.Fab")
		)
		(fp_line
			(start 0.67945 -0.3048)
			(end 0.67945 0.3048)
			(stroke
				(width 0.1)
				(type default)
			)
			(layer "F.Fab")
		)
		(fp_line
			(start 0.67945 0.3048)
			(end 0.120396 0.3048)
			(stroke
				(width 0.1)
				(type default)
			)
			(layer "F.Fab")
		)
		(pad "1" smd circle
			(at -0.40005 0)
			(size 0 0)
			(layers "F.Cu" "F.Mask" "F.Paste")
			(net "P3V3_AUX")
		)
		(pad "2" smd circle
			(at 0.40005 0)
			(size 0 0)
			(layers "F.Cu" "F.Mask" "F.Paste")
			(net "GPU_FPGA_OVERT_N")
		)
	)
)
